# S9S_MB_2U (Grand Teton) — schematic netlist excerpt (pin names and nets, part order shuffled) for the footprints in the layout excerpt that follows; sources: Cadence DE-HDL packaged netlist, KiCad conversion of 03242023_DA0F0TMBIJ0_F0T_Motherboard_J_brd_V01_OCP.brd

C257  Q_CAP  10UF 6.3V 20% X6S  pkg C0402  page 77 : A = PVCCIN_CPU1 ; B = GND
R1407  Q_RES  2K 1% CHIP  pkg 0402LF  page 219 : A = FM_PVCCINFAON_CPU0_R_EN ; B = GND

(kicad_pcb
	(version 20260206)
	(generator "pcbnew")
	(generator_version "10.0")
	(general
		(thickness 1.6)
		(legacy_teardrops no)
	)
	(paper "A4")
	(title_block
		(title "03242023_DA0F0TMBIJ0_F0T_Motherboard_J_brd_V01_OCP.brd")
		(comment 1 "Grand Teton / footprints 2540-2542 of 6105")
	)
	(layers
		(0 "F.Cu" signal "TOP")
		(4 "In1.Cu" signal "GND")
		(6 "In2.Cu" signal "IN1")
		(8 "In3.Cu" signal "GND1")
		(10 "In4.Cu" signal "IN2")
		(12 "In5.Cu" signal "GND2")
		(14 "In6.Cu" signal "IN3")
		(16 "In7.Cu" signal "GND3")
		(18 "In8.Cu" signal "VCC")
		(20 "In9.Cu" signal "VCC1")
		(22 "In10.Cu" signal "GND4")
		(24 "In11.Cu" signal "IN4")
		(26 "In12.Cu" signal "GND5")
		(28 "In13.Cu" signal "IN5")
		(30 "In14.Cu" signal "GND6")
		(32 "In15.Cu" signal "IN6")
		(34 "In16.Cu" signal "GND7")
		(2 "B.Cu" signal "BOTTOM")
		(9 "F.Adhes" user "F.Adhesive")
		(11 "B.Adhes" user "B.Adhesive")
		(13 "F.Paste" user "Package Geometry/Pastemask Top")
		(15 "B.Paste" user "Package Geometry/Pastemask Bottom")
		(5 "F.SilkS" user "Ref Des/Silkscreen Top")
		(7 "B.SilkS" user "Ref Des/Silkscreen Bottom")
		(1 "F.Mask" user "Board Geometry/Soldermask Top")
		(3 "B.Mask" user "Board Geometry/Soldermask Bottom")
		(17 "Dwgs.User" user "User.Drawings")
		(19 "Cmts.User" user "User.Comments")
		(21 "Eco1.User" user "User.Eco1")
		(23 "Eco2.User" user "User.Eco2")
		(25 "Edge.Cuts" user "Board Geometry/Outline")
		(27 "Margin" user)
		(31 "F.CrtYd" user "Package Geometry/Place Bound Top")
		(29 "B.CrtYd" user "Package Geometry/Place Bound Bottom")
		(35 "F.Fab" user "Ref Des/Assembly Top")
		(33 "B.Fab" user "Ref Des/Assembly Bottom")
	)
	(footprint ""
		(layer "F.Cu")
		(at 160.83788 -120.106948 180)
		(property "Reference" "R1407"
			(at 0 0 180)
			(layer "F.SilkS")
			(hide yes)
			(effects
				(font
					(size 1.27 1.27)
				)
			)
		)
		(property "Value" ""
			(at 0 0 180)
			(layer "F.Fab")
			(effects
				(font
					(size 1.27 1.27)
				)
			)
		)
		(duplicate_pad_numbers_are_jumpers no)
		(fp_line
			(start 0.7874 0.4064)
			(end -0.7874 0.4064)
			(stroke
				(width 0.1524)
				(type default)
			)
			(layer "F.SilkS")
		)
		(fp_line
			(start 0.7874 -0.4064)
			(end 0.7874 0.4064)
			(stroke
				(width 0.1524)
				(type default)
			)
			(layer "F.SilkS")
		)
		(fp_line
			(start -0.7874 0.4064)
			(end -0.7874 -0.4064)
			(stroke
				(width 0.1524)
				(type default)
			)
			(layer "F.SilkS")
		)
		(fp_line
			(start -0.7874 -0.4064)
			(end 0.7874 -0.4064)
			(stroke
				(width 0.1524)
				(type default)
			)
			(layer "F.SilkS")
		)
		(fp_line
			(start 0.67945 0.3048)
			(end 0.120396 0.3048)
			(stroke
				(width 0.1)
				(type default)
			)
			(layer "F.Fab")
		)
		(fp_line
			(start 0.67945 -0.3048)
			(end 0.67945 0.3048)
			(stroke
				(width 0.1)
				(type default)
			)
			(layer "F.Fab")
		)
		(fp_line
			(start 0.12065 -0.2794)
			(end 0.12065 -0.3048)
			(stroke
				(width 0.1)
				(type default)
			)
			(layer "F.Fab")
		)
		(fp_line
			(start 0.12065 -0.3048)
			(end 0.67945 -0.3048)
			(stroke
				(width 0.1)
				(type default)
			)
			(layer "F.Fab")
		)
		(fp_line
			(start 0.120396 0.3048)
			(end 0.120396 0.2794)
			(stroke
				(width 0.1)
				(type default)
			)
			(layer "F.Fab")
		)
		(fp_line
			(start 0.120396 0.2794)
			(end -0.12065 0.2794)
			(stroke
				(width 0.1)
				(type default)
			)
			(layer "F.Fab")
		)
		(fp_line
			(start -0.12065 0.3048)
			(end -0.67945 0.3048)
			(stroke
				(width 0.1)
				(type default)
			)
			(layer "F.Fab")
		)
		(fp_line
			(start -0.12065 0.2794)
			(end -0.12065 0.3048)
			(stroke
				(width 0.1)
				(type default)
			)
			(layer "F.Fab")
		)
		(fp_line
			(start -0.12065 -0.2794)
			(end 0.12065 -0.2794)
			(stroke
				(width 0.1)
				(type default)
			)
			(layer "F.Fab")
		)
		(fp_line
			(start -0.12065 -0.305054)
			(end -0.12065 -0.2794)
			(stroke
				(width 0.1)
				(type default)
			)
			(layer "F.Fab")
		)
		(fp_line
			(start -0.67945 0.3048)
			(end -0.67945 -0.305054)
			(stroke
				(width 0.1)
				(type default)
			)
			(layer "F.Fab")
		)
		(fp_line
			(start -0.67945 -0.305054)
			(end -0.12065 -0.305054)
			(stroke
				(width 0.1)
				(type default)
			)
			(layer "F.Fab")
		)
		(pad "1" smd circle
			(at -0.40005 0 180)
			(size 0 0)
			(layers "F.Cu" "F.Mask" "F.Paste")
			(net "FM_PVCCINFAON_CPU0_R_EN")
		)
		(pad "2" smd circle
			(at 0.40005 0 180)
			(size 0 0)
			(layers "F.Cu" "F.Mask" "F.Paste")
			(net "GND")
		)
	)
	(footprint ""
		(layer "F.Cu")
		(at 105.315004 -244.032024 90)
		(property "Reference" "C257"
			(at 0 0 90)
			(layer "F.SilkS")
			(hide yes)
			(effects
				(font
					(size 1.27 1.27)
				)
			)
		)
		(property "Value" ""
			(at 0 0 90)
			(layer "F.Fab")
			(effects
				(font
					(size 1.27 1.27)
				)
			)
		)
		(duplicate_pad_numbers_are_jumpers no)
		(fp_line
			(start 0.7874 -0.4064)
			(end 0.7874 0.4064)
			(stroke
				(width 0.1524)
				(type default)
			)
			(layer "F.SilkS")
		)
		(fp_line
			(start -0.7874 -0.4064)
			(end 0.7874 -0.4064)
			(stroke
				(width 0.1524)
				(type default)
			)
			(layer "F.SilkS")
		)
		(fp_line
			(start 0.7874 0.4064)
			(end -0.7874 0.4064)
			(stroke
				(width 0.1524)
				(type default)
			)
			(layer "F.SilkS")
		)
		(fp_line
			(start -0.7874 0.4064)
			(end -0.7874 -0.4064)
			(stroke
				(width 0.1524)
				(type default)
			)
			(layer "F.SilkS")
		)
		(fp_line
			(start -0.12065 -0.305054)
			(end -0.12065 -0.2794)
			(stroke
				(width 0.1)
				(type default)
			)
			(layer "F.Fab")
		)
		(fp_line
			(start -0.67945 -0.305054)
			(end -0.12065 -0.305054)
			(stroke
				(width 0.1)
				(type default)
			)
			(layer "F.Fab")
		)
		(fp_line
			(start 0.67945 -0.3048)
			(end 0.67945 0.3048)
			(stroke
				(width 0.1)
				(type default)
			)
			(layer "F.Fab")
		)
		(fp_line
			(start 0.12065 -0.3048)
			(end 0.67945 -0.3048)
			(stroke
				(width 0.1)
				(type default)
			)
			(layer "F.Fab")
		)
		(fp_line
			(start 0.12065 -0.2794)
			(end 0.12065 -0.3048)
			(stroke
				(width 0.1)
				(type default)
			)
			(layer "F.Fab")
		)
		(fp_line
			(start -0.12065 -0.2794)
			(end 0.12065 -0.2794)
			(stroke
				(width 0.1)
				(type default)
			)
			(layer "F.Fab")
		)
		(fp_line
			(start 0.120396 0.2794)
			(end -0.12065 0.2794)
			(stroke
				(width 0.1)
				(type default)
			)
			(layer "F.Fab")
		)
		(fp_line
			(start -0.12065 0.2794)
			(end -0.12065 0.3048)
			(stroke
				(width 0.1)
				(type default)
			)
			(layer "F.Fab")
		)
		(fp_line
			(start 0.67945 0.3048)
			(end 0.120396 0.3048)
			(stroke
				(width 0.1)
				(type default)
			)
			(layer "F.Fab")
		)
		(fp_line
			(start 0.120396 0.3048)
			(end 0.120396 0.2794)
			(stroke
				(width 0.1)
				(type default)
			)
			(layer "F.Fab")
		)
		(fp_line
			(start -0.12065 0.3048)
			(end -0.67945 0.3048)
			(stroke
				(width 0.1)
				(type default)
			)
			(layer "F.Fab")
		)
		(fp_line
			(start -0.67945 0.3048)
			(end -0.67945 -0.305054)
			(stroke
				(width 0.1)
				(type default)
			)
			(layer "F.Fab")
		)
		(pad "1" smd circle
			(at -0.40005 0 90)
			(size 0 0)
			(layers "F.Cu" "F.Mask" "F.Paste")
			(net "PVCCIN_CPU1")
		)
		(pad "2" smd circle
			(at 0.40005 0 90)
			(size 0 0)
			(layers "F.Cu" "F.Mask" "F.Paste")
			(net "GND")
		)
	)
	(footprint ""
		(layer "F.Cu")
		(at 236.93628 -332.849728)
		(property "Reference" ""
			(at 0 0 0)
			(layer "F.SilkS")
			(hide yes)
			(effects
				(font
					(size 1.27 1.27)
				)
			)
		)
		(property "Value" ""
			(at 0 0 0)
			(layer "F.Fab")
			(effects
				(font
					(size 1.27 1.27)
				)
			)
		)
		(duplicate_pad_numbers_are_jumpers no)
		(pad "1" smd circle
			(at 0 0)
			(size 0.9906 0.9906)
			(layers "F.Cu" "F.Mask" "F.Paste")
			(net "Net_294")
		)
		(zone
			(layer "F.Cu")
			(hatch none 0.5)
			(connect_pads
				(clearance 0)
			)
			(min_thickness 0.25)
			(keepout
				(tracks not_allowed)
				(vias allowed)
				(pads allowed)
				(copperpour not_allowed)
				(footprints allowed)
			)
			(placement
				(enabled no)
				(sheetname "")
			)
			(fill
				(thermal_gap 0.5)
				(thermal_bridge_width 0.5)
				(island_removal_mode 0)
			)
			(polygon
				(pts
					(arc
						(start 238.56188 -332.849728)
						(mid 235.31068 -332.849728)
						(end 238.56188 -332.849728)
					)
				)
			)
		)
	)
)
